# BASEBOARD_FAB2 (Tioga Pass) — schematic netlist excerpt (pin names and nets, part order shuffled) for the footprints in the layout excerpt that follows; sources: Cadence DE-HDL packaged netlist, KiCad conversion of Wiwynn_Tioga_Pass_MB.brd

C2L24  CAP_A  0.01UF 25V 10% X7R  pkg 0402V  page 173 : A = SATA6G_P7_TX_C_DP ; B = SATA6G_PCH_PCIE_UP_SATA_TXP<7>
R3N19  RES  10.0 1% CHIP  pkg 0402  page 211 : A = VSENSE_PVCCIO_CPU0_AVSP ; B = VR_PVCCIO_CPU0_AVSP
C9N14  CAP  0.22UF 16V 10% X7R  pkg 0402  page 182 : A = P3E_CPU1_PE3_MP_C_TXP<12> ; B = P3E_CPU1_PE3_MP_TXP<12>

(kicad_pcb
	(version 20260206)
	(generator "pcbnew")
	(generator_version "10.0")
	(general
		(thickness 1.6)
		(legacy_teardrops no)
	)
	(paper "A4")
	(title_block
		(title "Wiwynn_Tioga_Pass_MB.brd")
		(comment 1 "Tioga Pass / footprints 3384-3386 of 4770")
	)
	(layers
		(0 "F.Cu" signal "TOP")
		(4 "In1.Cu" signal "L2GND")
		(6 "In2.Cu" signal "L3")
		(8 "In3.Cu" signal "L4GND")
		(10 "In4.Cu" signal "L5")
		(12 "In5.Cu" signal "L6GND")
		(14 "In6.Cu" signal "L7VCC")
		(16 "In7.Cu" signal "L8VCC")
		(18 "In8.Cu" signal "L9GND")
		(20 "In9.Cu" signal "L10")
		(22 "In10.Cu" signal "L11GND")
		(24 "In11.Cu" signal "L12")
		(26 "In12.Cu" signal "L13GND")
		(2 "B.Cu" signal "BOTTOM")
		(9 "F.Adhes" user "F.Adhesive")
		(11 "B.Adhes" user "B.Adhesive")
		(13 "F.Paste" user "Package Geometry/Pastemask Top")
		(15 "B.Paste" user "Package Geometry/Pastemask Bottom")
		(5 "F.SilkS" user "Ref Des/Silkscreen Top")
		(7 "B.SilkS" user "Ref Des/Silkscreen Bottom")
		(1 "F.Mask" user "Board Geometry/Soldermask Top")
		(3 "B.Mask" user "Board Geometry/Soldermask Bottom")
		(17 "Dwgs.User" user "User.Drawings")
		(19 "Cmts.User" user "User.Comments")
		(21 "Eco1.User" user "User.Eco1")
		(23 "Eco2.User" user "User.Eco2")
		(25 "Edge.Cuts" user "Board Geometry/Outline")
		(27 "Margin" user)
		(31 "F.CrtYd" user "Package Geometry/Place Bound Top")
		(29 "B.CrtYd" user "Package Geometry/Place Bound Bottom")
		(35 "F.Fab" user "Ref Des/Assembly Top")
		(33 "B.Fab" user "Ref Des/Assembly Bottom")
	)
	(footprint ""
		(layer "B.Cu")
		(at 339.717126 -90.049604 90)
		(property "Reference" "R3N19"
			(at 0 0 90)
			(layer "B.SilkS")
			(hide yes)
			(effects
				(font
					(size 1.27 1.27)
				)
				(justify mirror)
			)
		)
		(property "Value" ""
			(at 0 0 90)
			(layer "B.Fab")
			(effects
				(font
					(size 1.27 1.27)
				)
				(justify mirror)
			)
		)
		(duplicate_pad_numbers_are_jumpers no)
		(fp_poly
			(pts
				(xy 0.2794 -0.1016) (xy -0.2794 -0.1016) (xy -0.2794 0.9906) (xy 0.2794 0.9906)
			)
			(stroke
				(width 0)
				(type default)
			)
			(fill no)
			(layer "B.CrtYd")
		)
		(fp_line
			(start 0.2794 -0.1016)
			(end 0.2794 0.9906)
			(stroke
				(width 0.1)
				(type default)
			)
			(layer "B.Fab")
		)
		(fp_line
			(start -0.2794 -0.1016)
			(end 0.2794 -0.1016)
			(stroke
				(width 0.1)
				(type default)
			)
			(layer "B.Fab")
		)
		(fp_line
			(start 0.2794 0.9906)
			(end -0.2794 0.9906)
			(stroke
				(width 0.1)
				(type default)
			)
			(layer "B.Fab")
		)
		(fp_line
			(start -0.2794 0.9906)
			(end -0.2794 -0.1016)
			(stroke
				(width 0.1)
				(type default)
			)
			(layer "B.Fab")
		)
		(pad "1" smd rect
			(at 0 0 270)
			(size 0.508 0.508)
			(layers "B.Cu" "B.Mask" "B.Paste")
			(net "VSENSE_PVCCIO_CPU0_AVSP")
		)
		(pad "2" smd rect
			(at 0 0.889 270)
			(size 0.508 0.508)
			(layers "B.Cu" "B.Mask" "B.Paste")
			(net "VR_PVCCIO_CPU0_AVSP")
		)
		(zone
			(layer "B.Cu")
			(hatch none 0.5)
			(connect_pads
				(clearance 0)
			)
			(min_thickness 0.25)
			(keepout
				(tracks allowed)
				(vias not_allowed)
				(pads allowed)
				(copperpour not_allowed)
				(footprints allowed)
			)
			(placement
				(enabled no)
				(sheetname "")
			)
			(fill
				(thermal_gap 0.5)
				(thermal_bridge_width 0.5)
				(island_removal_mode 0)
			)
			(polygon
				(pts
					(xy 339.971126 -90.303604) (xy 339.971126 -89.795604) (xy 340.352126 -89.795604) (xy 340.352126 -90.303604)
				)
			)
		)
		(zone
			(layer "B.Cu")
			(hatch none 0.5)
			(connect_pads
				(clearance 0)
			)
			(min_thickness 0.25)
			(keepout
				(tracks not_allowed)
				(vias allowed)
				(pads allowed)
				(copperpour not_allowed)
				(footprints allowed)
			)
			(placement
				(enabled no)
				(sheetname "")
			)
			(fill
				(thermal_gap 0.5)
				(thermal_bridge_width 0.5)
				(island_removal_mode 0)
			)
			(polygon
				(pts
					(xy 340.352126 -90.303604) (xy 340.352126 -89.795604) (xy 339.971126 -89.795604) (xy 339.971126 -90.303604)
				)
			)
		)
	)
	(footprint ""
		(layer "B.Cu")
		(at 13.11402 -100.46208 90)
		(property "Reference" "C9N14"
			(at 0 0 90)
			(layer "B.SilkS")
			(hide yes)
			(effects
				(font
					(size 1.27 1.27)
				)
				(justify mirror)
			)
		)
		(property "Value" ""
			(at 0 0 90)
			(layer "B.Fab")
			(effects
				(font
					(size 1.27 1.27)
				)
				(justify mirror)
			)
		)
		(duplicate_pad_numbers_are_jumpers no)
		(fp_poly
			(pts
				(xy -0.3048 -0.1016) (xy -0.3048 0.9906) (xy 0.3048 0.9906) (xy 0.3048 -0.1016)
			)
			(stroke
				(width 0)
				(type default)
			)
			(fill no)
			(layer "B.CrtYd")
		)
		(fp_line
			(start 0.3048 -0.1016)
			(end 0.3048 0.9906)
			(stroke
				(width 0.1)
				(type default)
			)
			(layer "B.Fab")
		)
		(fp_line
			(start -0.3048 -0.1016)
			(end 0.3048 -0.1016)
			(stroke
				(width 0.1)
				(type default)
			)
			(layer "B.Fab")
		)
		(fp_line
			(start 0.3048 0.9906)
			(end -0.3048 0.9906)
			(stroke
				(width 0.1)
				(type default)
			)
			(layer "B.Fab")
		)
		(fp_line
			(start -0.3048 0.9906)
			(end -0.3048 -0.1016)
			(stroke
				(width 0.1)
				(type default)
			)
			(layer "B.Fab")
		)
		(pad "1" smd rect
			(at 0 0 270)
			(size 0.508 0.508)
			(layers "B.Cu" "B.Mask" "B.Paste")
			(net "P3E_CPU1_PE3_MP_C_TXP<12>")
		)
		(pad "2" smd rect
			(at 0 0.889 270)
			(size 0.508 0.508)
			(layers "B.Cu" "B.Mask" "B.Paste")
			(net "P3E_CPU1_PE3_MP_TXP<12>")
		)
		(zone
			(layer "B.Cu")
			(hatch none 0.5)
			(connect_pads
				(clearance 0)
			)
			(min_thickness 0.25)
			(keepout
				(tracks allowed)
				(vias not_allowed)
				(pads allowed)
				(copperpour not_allowed)
				(footprints allowed)
			)
			(placement
				(enabled no)
				(sheetname "")
			)
			(fill
				(thermal_gap 0.5)
				(thermal_bridge_width 0.5)
				(island_removal_mode 0)
			)
			(polygon
				(pts
					(xy 13.36802 -100.71608) (xy 13.36802 -100.20808) (xy 13.74902 -100.20808) (xy 13.74902 -100.71608)
				)
			)
		)
		(zone
			(layer "B.Cu")
			(hatch none 0.5)
			(connect_pads
				(clearance 0)
			)
			(min_thickness 0.25)
			(keepout
				(tracks not_allowed)
				(vias allowed)
				(pads allowed)
				(copperpour not_allowed)
				(footprints allowed)
			)
			(placement
				(enabled no)
				(sheetname "")
			)
			(fill
				(thermal_gap 0.5)
				(thermal_bridge_width 0.5)
				(island_removal_mode 0)
			)
			(polygon
				(pts
					(xy 13.74902 -100.71608) (xy 13.74902 -100.20808) (xy 13.36802 -100.20808) (xy 13.36802 -100.71608)
				)
			)
		)
	)
	(footprint ""
		(layer "B.Cu")
		(at 409.6004 -146.939 -90)
		(property "Reference" "C2L24"
			(at 0 0 90)
			(layer "B.SilkS")
			(hide yes)
			(effects
				(font
					(size 1.27 1.27)
				)
				(justify mirror)
			)
		)
		(property "Value" ""
			(at 0 0 90)
			(layer "B.Fab")
			(effects
				(font
					(size 1.27 1.27)
				)
				(justify mirror)
			)
		)
		(duplicate_pad_numbers_are_jumpers no)
		(fp_poly
			(pts
				(xy -0.3048 -0.1016) (xy -0.3048 0.9906) (xy 0.3048 0.9906) (xy 0.3048 -0.1016)
			)
			(stroke
				(width 0)
				(type default)
			)
			(fill no)
			(layer "B.CrtYd")
		)
		(fp_line
			(start -0.3048 0.9906)
			(end -0.3048 -0.1016)
			(stroke
				(width 0.1)
				(type default)
			)
			(layer "B.Fab")
		)
		(fp_line
			(start 0.3048 0.9906)
			(end -0.3048 0.9906)
			(stroke
				(width 0.1)
				(type default)
			)
			(layer "B.Fab")
		)
		(fp_line
			(start -0.3048 -0.1016)
			(end 0.3048 -0.1016)
			(stroke
				(width 0.1)
				(type default)
			)
			(layer "B.Fab")
		)
		(fp_line
			(start 0.3048 -0.1016)
			(end 0.3048 0.9906)
			(stroke
				(width 0.1)
				(type default)
			)
			(layer "B.Fab")
		)
		(pad "1" smd rect
			(at 0 0 90)
			(size 0.508 0.508)
			(layers "B.Cu" "B.Mask" "B.Paste")
			(net "SATA6G_P7_TX_C_DP")
		)
		(pad "2" smd rect
			(at 0 0.889 90)
			(size 0.508 0.508)
			(layers "B.Cu" "B.Mask" "B.Paste")
			(net "SATA6G_PCH_PCIE_UP_SATA_TXP<7>")
		)
		(zone
			(layer "B.Cu")
			(hatch none 0.5)
			(connect_pads
				(clearance 0)
			)
			(min_thickness 0.25)
			(keepout
				(tracks not_allowed)
				(vias allowed)
				(pads allowed)
				(copperpour not_allowed)
				(footprints allowed)
			)
			(placement
				(enabled no)
				(sheetname "")
			)
			(fill
				(thermal_gap 0.5)
				(thermal_bridge_width 0.5)
				(island_removal_mode 0)
			)
			(polygon
				(pts
					(xy 408.9654 -146.685) (xy 408.9654 -147.193) (xy 409.3464 -147.193) (xy 409.3464 -146.685)
				)
			)
		)
		(zone
			(layer "B.Cu")
			(hatch none 0.5)
			(connect_pads
				(clearance 0)
			)
			(min_thickness 0.25)
			(keepout
				(tracks allowed)
				(vias not_allowed)
				(pads allowed)
				(copperpour not_allowed)
				(footprints allowed)
			)
			(placement
				(enabled no)
				(sheetname "")
			)
			(fill
				(thermal_gap 0.5)
				(thermal_bridge_width 0.5)
				(island_removal_mode 0)
			)
			(polygon
				(pts
					(xy 409.3464 -146.685) (xy 409.3464 -147.193) (xy 408.9654 -147.193) (xy 408.9654 -146.685)
				)
			)
		)
	)
)
